FILE_TYPE=LIBRARY_PARTS;
primitive 'DIODEAC_DUAL_ARRAY','DIODEAC_DUAL_ARRAY_SM','DIODEAC_DUAL_ARRAY_SMLF';
  pin
    'A1<0>':
      PIN_NUMBER='(1,4)';
      PINUSE='UNSPEC';
      NO_LOAD_CHECK='BOTH';
      NO_IO_CHECK='BOTH';
      ALLOW_CONNECT='TRUE';
    'C1_A2<0>':
      PIN_NUMBER='(6,3)';
      PINUSE='UNSPEC';
      NO_LOAD_CHECK='BOTH';
      NO_IO_CHECK='BOTH';
      ALLOW_CONNECT='TRUE';
    'C2<0>':
      PIN_NUMBER='(2,5)';
      PINUSE='UNSPEC';
      NO_LOAD_CHECK='BOTH';
      NO_IO_CHECK='BOTH';
      ALLOW_CONNECT='TRUE';
  end_pin;
  body
    PART_NAME='DIODEAC_DUAL_ARRAY';
    PHYS_DES_PREFIX='CR';
  end_body;
end_primitive;
primitive 'DIODEAC_DUAL_ARRAY_SM24LF';
  pin
    'AC0':
      PIN_NUMBER='(2)';
      BIDIRECTIONAL='TRUE';
      INPUT_LOAD='(-0.01,0.01)';
      OUTPUT_LOAD='(1.0,-1.0)';
    'AC1':
      PIN_NUMBER='(3)';
      BIDIRECTIONAL='TRUE';
      INPUT_LOAD='(-0.01,0.01)';
      OUTPUT_LOAD='(1.0,-1.0)';
    'AC10':
      PIN_NUMBER='(15)';
      BIDIRECTIONAL='TRUE';
      INPUT_LOAD='(-0.01,0.01)';
      OUTPUT_LOAD='(1.0,-1.0)';
    'AC11':
      PIN_NUMBER='(16)';
      BIDIRECTIONAL='TRUE';
      INPUT_LOAD='(-0.01,0.01)';
      OUTPUT_LOAD='(1.0,-1.0)';
    'AC12':
      PIN_NUMBER='(17)';
      BIDIRECTIONAL='TRUE';
      INPUT_LOAD='(-0.01,0.01)';
      OUTPUT_LOAD='(1.0,-1.0)';
    'AC13':
      PIN_NUMBER='(18)';
      BIDIRECTIONAL='TRUE';
      INPUT_LOAD='(-0.01,0.01)';
      OUTPUT_LOAD='(1.0,-1.0)';
    'AC14':
      PIN_NUMBER='(20)';
      BIDIRECTIONAL='TRUE';
      INPUT_LOAD='(-0.01,0.01)';
      OUTPUT_LOAD='(1.0,-1.0)';
    'AC15':
      PIN_NUMBER='(21)';
      BIDIRECTIONAL='TRUE';
      INPUT_LOAD='(-0.01,0.01)';
      OUTPUT_LOAD='(1.0,-1.0)';
    'AC16':
      PIN_NUMBER='(22)';
      BIDIRECTIONAL='TRUE';
      INPUT_LOAD='(-0.01,0.01)';
      OUTPUT_LOAD='(1.0,-1.0)';
    'AC17':
      PIN_NUMBER='(23)';
      BIDIRECTIONAL='TRUE';
      INPUT_LOAD='(-0.01,0.01)';
      OUTPUT_LOAD='(1.0,-1.0)';
    'AC2':
      PIN_NUMBER='(4)';
      BIDIRECTIONAL='TRUE';
      INPUT_LOAD='(-0.01,0.01)';
      OUTPUT_LOAD='(1.0,-1.0)';
    'AC3':
      PIN_NUMBER='(5)';
      BIDIRECTIONAL='TRUE';
      INPUT_LOAD='(-0.01,0.01)';
      OUTPUT_LOAD='(1.0,-1.0)';
    'AC4':
      PIN_NUMBER='(7)';
      BIDIRECTIONAL='TRUE';
      INPUT_LOAD='(-0.01,0.01)';
      OUTPUT_LOAD='(1.0,-1.0)';
    'AC5':
      PIN_NUMBER='(8)';
      BIDIRECTIONAL='TRUE';
      INPUT_LOAD='(-0.01,0.01)';
      OUTPUT_LOAD='(1.0,-1.0)';
    'AC6':
      PIN_NUMBER='(9)';
      BIDIRECTIONAL='TRUE';
      INPUT_LOAD='(-0.01,0.01)';
      OUTPUT_LOAD='(1.0,-1.0)';
    'AC7':
      PIN_NUMBER='(10)';
      BIDIRECTIONAL='TRUE';
      INPUT_LOAD='(-0.01,0.01)';
      OUTPUT_LOAD='(1.0,-1.0)';
    'AC8':
      PIN_NUMBER='(11)';
      BIDIRECTIONAL='TRUE';
      INPUT_LOAD='(-0.01,0.01)';
      OUTPUT_LOAD='(1.0,-1.0)';
    'AC9':
      PIN_NUMBER='(14)';
      BIDIRECTIONAL='TRUE';
      INPUT_LOAD='(-0.01,0.01)';
      OUTPUT_LOAD='(1.0,-1.0)';
    'GND'<2>:
      PIN_NUMBER='(13)';
      PINUSE='GROUND';
      NO_LOAD_CHECK='Both';
      NO_IO_CHECK='Both';
      NO_ASSERT_CHECK='TRUE';
      NO_DIR_CHECK='TRUE';
      ALLOW_CONNECT='TRUE';
    'GND'<1>:
      PIN_NUMBER='(6)';
      PINUSE='GROUND';
      NO_LOAD_CHECK='Both';
      NO_IO_CHECK='Both';
      NO_ASSERT_CHECK='TRUE';
      NO_DIR_CHECK='TRUE';
      ALLOW_CONNECT='TRUE';
    'GND'<0>:
      PIN_NUMBER='(1)';
      PINUSE='GROUND';
      NO_LOAD_CHECK='Both';
      NO_IO_CHECK='Both';
      NO_ASSERT_CHECK='TRUE';
      NO_DIR_CHECK='TRUE';
      ALLOW_CONNECT='TRUE';
    'VDD'<2>:
      PIN_NUMBER='(24)';
      PINUSE='POWER';
      NO_LOAD_CHECK='Both';
      NO_IO_CHECK='Both';
      NO_ASSERT_CHECK='TRUE';
      NO_DIR_CHECK='TRUE';
      ALLOW_CONNECT='TRUE';
    'VDD'<1>:
      PIN_NUMBER='(19)';
      PINUSE='POWER';
      NO_LOAD_CHECK='Both';
      NO_IO_CHECK='Both';
      NO_ASSERT_CHECK='TRUE';
      NO_DIR_CHECK='TRUE';
      ALLOW_CONNECT='TRUE';
    'VDD'<0>:
      PIN_NUMBER='(12)';
      PINUSE='POWER';
      NO_LOAD_CHECK='Both';
      NO_IO_CHECK='Both';
      NO_ASSERT_CHECK='TRUE';
      NO_DIR_CHECK='TRUE';
      ALLOW_CONNECT='TRUE';
  end_pin;
  body
    PART_NAME='DIODEAC_DUAL_ARRAY';
    PHYS_DES_PREFIX='CR';
  end_body;
end_primitive;
primitive 'DIODEAC_DUAL_ARRAY_SM6LF';
  pin
    'AC1':
      PIN_NUMBER='(1)';
      BIDIRECTIONAL='TRUE';
      INPUT_LOAD='(-0.01,0.01)';
      OUTPUT_LOAD='(1.0,-1.0)';
    'AC2':
      PIN_NUMBER='(3)';
      BIDIRECTIONAL='TRUE';
      INPUT_LOAD='(-0.01,0.01)';
      OUTPUT_LOAD='(1.0,-1.0)';
    'AC3':
      PIN_NUMBER='(4)';
      BIDIRECTIONAL='TRUE';
      INPUT_LOAD='(-0.01,0.01)';
      OUTPUT_LOAD='(1.0,-1.0)';
    'AC4':
      PIN_NUMBER='(6)';
      BIDIRECTIONAL='TRUE';
      INPUT_LOAD='(-0.01,0.01)';
      OUTPUT_LOAD='(1.0,-1.0)';
    'GND<0>':
      PIN_NUMBER='(2)';
      PINUSE='GROUND';
      NO_LOAD_CHECK='Both';
      NO_IO_CHECK='Both';
      NO_ASSERT_CHECK='TRUE';
      NO_DIR_CHECK='TRUE';
      ALLOW_CONNECT='TRUE';
    'VP':
      PIN_NUMBER='(5)';
      PINUSE='POWER';
      NO_LOAD_CHECK='Both';
      NO_IO_CHECK='Both';
      NO_ASSERT_CHECK='TRUE';
      NO_DIR_CHECK='TRUE';
      ALLOW_CONNECT='TRUE';
  end_pin;
  body
    PART_NAME='DIODEAC_DUAL_ARRAY';
    PHYS_DES_PREFIX='CR';
  end_body;
end_primitive;
primitive 'DIODEAC_DUAL_ARRAY_SM9';
  pin
    'AC0':
      PIN_NUMBER='(1)';
      BIDIRECTIONAL='TRUE';
      INPUT_LOAD='(-0.01,0.01)';
      OUTPUT_LOAD='(1.0,-1.0)';
    'AC1':
      PIN_NUMBER='(2)';
      BIDIRECTIONAL='TRUE';
      INPUT_LOAD='(-0.01,0.01)';
      OUTPUT_LOAD='(1.0,-1.0)';
    'AC2':
      PIN_NUMBER='(4)';
      BIDIRECTIONAL='TRUE';
      INPUT_LOAD='(-0.01,0.01)';
      OUTPUT_LOAD='(1.0,-1.0)';
    'AC3':
      PIN_NUMBER='(5)';
      BIDIRECTIONAL='TRUE';
      INPUT_LOAD='(-0.01,0.01)';
      OUTPUT_LOAD='(1.0,-1.0)';
    'GND<0>':
      PIN_NUMBER='(3)';
      PINUSE='GROUND';
      NO_LOAD_CHECK='Both';
      NO_IO_CHECK='Both';
      NO_ASSERT_CHECK='TRUE';
      NO_DIR_CHECK='TRUE';
      ALLOW_CONNECT='TRUE';
    'OUT0':
      PIN_NUMBER='(9)';
      OUTPUT_LOAD='(1.0,-1.0)';
    'OUT1':
      PIN_NUMBER='(8)';
      OUTPUT_LOAD='(1.0,-1.0)';
    'OUT2':
      PIN_NUMBER='(7)';
      OUTPUT_LOAD='(1.0,-1.0)';
    'OUT3':
      PIN_NUMBER='(6)';
      OUTPUT_LOAD='(1.0,-1.0)';
  end_pin;
  body
    PART_NAME='DIODEAC_DUAL_ARRAY';
    PHYS_DES_PREFIX='CR';
  end_body;
end_primitive;
END.
